# SCM (Grand Teton) — schematic netlist excerpt (pin names and nets, part order shuffled) for the footprints in the layout excerpt that follows; sources: Cadence DE-HDL packaged netlist, KiCad conversion of 12092022_DA0F0TMDCD0_F0T_Management_Board_D_brd_V3_OCP.brd

GF1  FCONN168_ME1016810202011_SCM  EMPTY  pkg GOLD_168P_ME1016813401311  page 10
  I2C_0_SCL  = SMB_BMC_MM14_R1_SCL
  I2C_0_SDA  = SMB_BMC_MM14_R1_SDA
  I2C_1_SCL  = SMB_BMC_MM1_SCL
  I2C_1_SDA  = SMB_BMC_MM1_SDA
  I2C_2_SCL  = SMB_BMC_MM2_SCL_R1
  I2C_2_SDA  = SMB_BMC_MM2_SDA
  I2C_3_SCL  = SMB_BMC_MM3_SCL
  I2C_3_SDA  = SMB_BMC_MM3_SDA
  I2C_4_SCL  = SMB_BMC_MM4_SCL
  I2C_4_SDA  = SMB_BMC_MM4_SDA
  I2C_5_SCL  = SMB_BMC_MM5_SCL
  I2C_5_SDA  = SMB_BMC_MM5_SDA
  GND_A13  = GND
  CLK_100M_PCIE_DP  = CLK_100M_PCH_DP
  CLK_100M_PCIE_DN  = CLK_100M_PCH_DN
  GND_A16  = GND
  PCIE_BMC_TX_DP  = P2E_PCH_RX_DP
  PCIE_BMC_TX_DN  = P2E_PCH_RX_DN
  GND_A19  = GND
  PCIE_BMC_RX_DP  = P2E_PCH_TX_C_DP
  PCIE_BMC_RX_DN  = P2E_PCH_TX_C_DN
  GND_A22  = GND
  I2C_6_SCL  = SMB_BMC_MM6_SCL
  I2C_6_SDA  = SMB_BMC_MM6_SDA
  I2C_7_SCL  = SMB_BMC_MM7_SCL
  I2C_7_SDA  = SMB_BMC_MM7_SDA
  I2C_8_SCL  = SMB_BMC_MM8_SCL
  I2C_8_SDA  = SMB_BMC_MM8_SDA
  I2C_9_SCL  = SMB_BMC_MM9_SCL
  I2C_9_SDA  = SMB_BMC_MM9_SDA
  I2C_10_SCL  = SMB_BMC_MM10_SCL
  I2C_10_SDA  = SMB_BMC_MM10_SDA
  GND_A33  = GND
  JTAG_TCK  = JTAG_MB_TCK
  JTAG_TMS  = JTAG_MB_TMS
  JTAG_TDI  = JTAG_MB_TDI
  JTAG_TDO  = JTAG_MB_TDO
  I2C_11_SCL  = SMB_BMC_MM12_SCL
  I2C_11_SDA  = SMB_BMC_MM12_SDA
  I2C_12_SCL  = SMB_BMC_MM13_SCL
  I2C_12_SDA  = SMB_BMC_MM13_SDA
  GND_A42  = GND
  HPM_FW_RECOVERY  = FM_JTAG_SEL
  HPM_STBY_RDY  = PWRGD_PSU_AC_PWROK_R
  HPM_STBY_EN  = TP_GF_A45
  HPM_STBY_RST_N  = RST_MB_STBY_N
  SYS_PWRBTN_N  = SYS_PWRBTN_N
  SYS_PWROK  = PWRGD_SYS_PWROK
  DBP_PREQ_N  = FM_DBP_CPU_PREQ_GF_R_N
  DBP_PRDY_N  = FM_DBP_BMC_PRDY_N
  RST_PLTRST_BUF_N  = RST_PLTRST_N
  SPARE1  = FM_BMC_UARTSW_MSB_N
  ROT_CPU_RST_N  = RST_ROT_CPU_N
  CHASI_N  = FM_INTRUDER_N
  SPARE0  = FM_BMC_UARTSW_LSB_N
  IRQ_N  = IRQ_SMI_ACTIVE_GF_N
  PRSNT1_N  = FM_PRSNT_1_N
  GND_A58  = GND
  PCIE_HPM_RXP_0  = USB3_FPNL_RXP
  PCIE_HPM_RXN_0  = USB3_FPNL_RXN
  GND_A61  = GND
  PCIE_HPM_RXP_1  = TP_GF_A62
  PCIE_HPM_RXN_1  = TP_GF_A63
  GND_A64  = GND
  PCIE_HPM_RXP_2  = P2E_GPU_RX_DP
  PCIE_HPM_RXN_2  = P2E_GPU_RX_DN
  GND_A67  = GND
  PCIE_HPM_RXP_3  = CLK_100M_GPU_DP
  PCIE_HPM_RXN_3  = CLK_100M_GPU_DN
  GND_A70  = GND
  ESPI_CLK  = ESPI_HOST_LPC_BMC_CLK
  ESPI_CS0_N  = ESPI_HOST_LPC_BMC_LFRAME_N
  ESPI_ALERT_N  = IRQ_BMC_LPC_SERIRQ_ESPI_GF
  ESPI_RESET_N  = RST_BMC_LPC_ESPI_N
  ESPI_IO0  = ESPI_LPC_LAD0_IO0
  ESPI_IO1  = ESPI_LPC_LAD1_IO1
  ESPI_IO2  = ESPI_LPC_LAD2_IO2
  ESPI_IO3  = ESPI_LPC_LAD3_IO3
  RSVD3  = LPC_ESPI_SEL
  GND_B10  = GND
  QSPI0_CLK  = SPI_SYS_R_CLK
  QSPI0_CS0_N  = SPI_SYS_CS0_N
  QSPI0_D0  = SPI_SYS_R_MOSI
  QSPI0_D1  = SPI_SYS_R_MISO
  QSPI0_D2  = SPI_SYS_WP_R_IO2
  QSPI0_D3  = SPI_SYS_HOLD_R_IO3
  GND_B17  = GND
  NCSI_CLK  = RMII_OCP_RCLKI
  NCSI_CRS_DV  = RMII_CSRDV
  NCSI_TXEN  = RMII_TXEN
  NCSI_TXD0  = RMII_TXD0
  NCSI_TXD1  = RMII_TXD1
  NCSI_RXER  = RMII_RXER
  NCSI_RXD0  = RMII_RXD0
  NCSI_RXD1  = RMII_RXD1
  GND_B26  = GND
  PECI_BMC  = PECI_BMC
  PVCCIO_PECI  = PVCCIO_PECI_BMC
  SGPIO0_DO  = SGPIO_DO_0
  SGPIO_CLK  = SGPIO_CLK_0
  SGPIO0_DI  = SGPIO_DI_0
  SGPIO0_LD  = SGPIO_LD_0
  GND_B33  = GND
  SGPIO1_DO  = SGPIO_DO_1
  RSVD2  = SGPIO_CLK_1
  SGPIO1_DI  = SGPIO_DI_1
  SGPIO1_LD  = SGPIO_LD_1
  GND_B38  = GND
  SGPIO_RESET_N  = RST_SGPIO_RESET_N
  SGPIO_INTR_N  = IRQ_SGPIO_N
  P3V0_BAT  = P3V_BAT_R
  QSPI0_CS1_N  = AC_PWR_BTN_N
  QSPI1_CLK  = QSPI_2_PLD_CLK
  QSPI1_CS0_N  = TP_GF1_B44
  QSPI1_D0  = QSPI_2_PLD_IO0
  QSPI1_D1  = QSPI_2_PLD_IO1
  QSPI1_D2  = QSPI_2_PLD_IO2
  QSPI1_D3  = QSPI_2_PLD_IO3
  GND_B49  = GND
  USB2_DP  = USB_HOST_BMC_B_DP
  USB2_DN  = USB_HOST_BMC_B_DN
  GND_B52  = GND
  USB1_DP  = USB_HOST_BMC_A_DP
  USB1_DN  = USB_HOST_BMC_A_DN
  GND_B55  = GND
  RSVD0  = USB_FPNL_DP
  RSVD1  = USB_FPNL_DN
  GND_B58  = GND
  PCIE_HPM_TXP_0  = USB3_FPNL_TXP
  PCIE_HPM_TXN_0  = USB3_FPNL_TXN
  GND_B61  = GND
  PCIE_HPM_TXP_1  = TP_GF_B62
  PCIE_HPM_TXN_1  = TP_GF_B63
  GND_B64  = GND
  PCIE_HPM_TXP_2  = P2E_GPU_TX_C_DP
  PCIE_HPM_TXN_2  = P2E_GPU_TX_C_DN
  GND_B67  = GND
  PCIE_HPM_TXP_3  = HDD_LED_R_N
  PCIE_HPM_TXN_3  = PCH_BEEP_R_LED
  GND_B70  = GND
  P12V_AUX_OA1  = P12V_AUX
  P12V_AUX_OA2  = P12V_AUX
  GND_OA3  = GND
  GND_OA4  = GND
  I3C_0_SCL  = I3C1_SPD_SCL
  I3C_0_SDA  = I3C1_SPD_SDA
  I3C_1_SCL  = I3C2_SPD_SCL
  I3C_1_SDA  = I3C2_SPD_SDA
  I3C_2_SCL  = I3C3_SPD_SCL
  I3C_2_SDA  = I3C3_SPD_SDA
  I3C_3_SCL  = I3C4_SPD_SCL
  I3C_3_SDA  = I3C4_SPD_SDA
  GND_OA13  = GND
  VIRTUAL_RESEAT  = FM_VIRTUAL_RESEAT
  P12V_AUX_OB1  = P12V_AUX
  P12V_AUX_OB2  = P12V_AUX
  PRSNT0_N  = FM_PRSNT_0_R_N
  GND_OB4  = GND
  UART1_SCM_TX  = UART_BIC_GF_TXD
  UART1_SCM_RX  = UART_BIC_GF_RXD
  GND_OB7  = GND
  UART0_SCM_TX  = UART_SYS_DBG_TX
  UART0_SCM_RX  = UART_SYS_DBG_RX
  GND_OB10  = GND
  SPI0_CLK  = RST_SRST_PLD_BMC_R_N
  SPI0_CS_N  = SPI_TPM_CS_N
  SPI0_MOSI  = H_CPU_CATERR_LVC2_R2_N
  SPI0_MISO  = FM_SOL_UART_CH_SEL

(kicad_pcb
	(version 20260206)
	(generator "pcbnew")
	(generator_version "10.0")
	(general
		(thickness 1.6)
		(legacy_teardrops no)
	)
	(paper "A4")
	(title_block
		(title "12092022_DA0F0TMDCD0_F0T_Management_Board_D_brd_V3_OCP.brd")
		(comment 1 "Grand Teton / footprint 804 of 1440 (GF1), pads 1-47 of 168")
	)
	(layers
		(0 "F.Cu" signal "TOP")
		(4 "In1.Cu" signal "GND")
		(6 "In2.Cu" signal "IN1")
		(8 "In3.Cu" signal "GND1")
		(10 "In4.Cu" signal "IN2")
		(12 "In5.Cu" signal "VCC")
		(14 "In6.Cu" signal "VCC1")
		(16 "In7.Cu" signal "IN3")
		(18 "In8.Cu" signal "GND2")
		(20 "In9.Cu" signal "IN4")
		(22 "In10.Cu" signal "GND3")
		(2 "B.Cu" signal "BOTTOM")
		(9 "F.Adhes" user "F.Adhesive")
		(11 "B.Adhes" user "B.Adhesive")
		(13 "F.Paste" user "Package Geometry/Pastemask Top")
		(15 "B.Paste" user "Package Geometry/Pastemask Bottom")
		(5 "F.SilkS" user "Ref Des/Silkscreen Top")
		(7 "B.SilkS" user "Ref Des/Silkscreen Bottom")
		(1 "F.Mask" user "Board Geometry/Soldermask Top")
		(3 "B.Mask" user "Board Geometry/Soldermask Bottom")
		(17 "Dwgs.User" user "User.Drawings")
		(19 "Cmts.User" user "User.Comments")
		(21 "Eco1.User" user "User.Eco1")
		(23 "Eco2.User" user "User.Eco2")
		(25 "Edge.Cuts" user "Board Geometry/Outline")
		(27 "Margin" user)
		(31 "F.CrtYd" user "Package Geometry/Place Bound Top")
		(29 "B.CrtYd" user "Package Geometry/Place Bound Bottom")
		(35 "F.Fab" user "Ref Des/Assembly Top")
		(33 "B.Fab" user "Ref Des/Assembly Bottom")
	)
	(footprint ""
		(layer "B.Cu")
		(at 45.260006 -114.324892 180)
		(property "Reference" "GF1"
			(at 30.591506 -4.763262 0)
			(unlocked yes)
			(layer "B.SilkS")
			(effects
				(font
					(size 0.7874 0.5842)
					(thickness 0.1524)
				)
				(justify left mirror)
			)
		)
		(property "Value" ""
			(at 0 0 0)
			(layer "B.Fab")
			(effects
				(font
					(size 1.27 1.27)
				)
				(justify mirror)
			)
		)
		(duplicate_pad_numbers_are_jumpers no)
		(pad "A1" smd rect
			(at -18.204942 4.13512)
			(size 0.381 2.1336)
			(layers "B.Cu" "B.Mask" "B.Paste")
			(net "SMB_BMC_MM14_R1_SCL")
		)
		(pad "A2" smd rect
			(at -17.604994 4.13512)
			(size 0.381 2.1336)
			(layers "B.Cu" "B.Mask" "B.Paste")
			(net "SMB_BMC_MM14_R1_SDA")
		)
		(pad "A3" smd rect
			(at -17.005046 4.13512)
			(size 0.381 2.1336)
			(layers "B.Cu" "B.Mask" "B.Paste")
			(net "SMB_BMC_MM1_SCL")
		)
		(pad "A4" smd rect
			(at -16.405098 4.13512)
			(size 0.381 2.1336)
			(layers "B.Cu" "B.Mask" "B.Paste")
			(net "SMB_BMC_MM1_SDA")
		)
		(pad "A5" smd rect
			(at -15.804896 4.13512)
			(size 0.381 2.1336)
			(layers "B.Cu" "B.Mask" "B.Paste")
			(net "SMB_BMC_MM2_SCL_R1")
		)
		(pad "A6" smd rect
			(at -15.204948 4.13512)
			(size 0.381 2.1336)
			(layers "B.Cu" "B.Mask" "B.Paste")
			(net "SMB_BMC_MM2_SDA")
		)
		(pad "A7" smd rect
			(at -14.605 3.934968)
			(size 0.381 1.7272)
			(layers "B.Cu" "B.Mask" "B.Paste")
			(net "SMB_BMC_MM3_SCL")
		)
		(pad "A8" smd rect
			(at -14.005052 3.934968)
			(size 0.381 1.7272)
			(layers "B.Cu" "B.Mask" "B.Paste")
			(net "SMB_BMC_MM3_SDA")
		)
		(pad "A9" smd rect
			(at -13.405104 3.934968)
			(size 0.381 1.7272)
			(layers "B.Cu" "B.Mask" "B.Paste")
			(net "SMB_BMC_MM4_SCL")
		)
		(pad "A10" smd rect
			(at -12.804902 3.934968)
			(size 0.381 1.7272)
			(layers "B.Cu" "B.Mask" "B.Paste")
			(net "SMB_BMC_MM4_SDA")
		)
		(pad "A11" smd rect
			(at -12.204954 3.934968)
			(size 0.381 1.7272)
			(layers "B.Cu" "B.Mask" "B.Paste")
			(net "SMB_BMC_MM5_SCL")
		)
		(pad "A12" smd rect
			(at -11.605006 3.934968)
			(size 0.381 1.7272)
			(layers "B.Cu" "B.Mask" "B.Paste")
			(net "SMB_BMC_MM5_SDA")
		)
		(pad "A13" smd rect
			(at -11.005058 4.13512)
			(size 0.381 2.1336)
			(layers "B.Cu" "B.Mask" "B.Paste")
			(net "GND")
		)
		(pad "A14" smd rect
			(at -10.40511 3.934968)
			(size 0.381 1.7272)
			(layers "B.Cu" "B.Mask" "B.Paste")
			(net "CLK_100M_PCH_DP")
		)
		(pad "A15" smd rect
			(at -9.804908 3.934968)
			(size 0.381 1.7272)
			(layers "B.Cu" "B.Mask" "B.Paste")
			(net "CLK_100M_PCH_DN")
		)
		(pad "A16" smd rect
			(at -9.20496 4.13512)
			(size 0.381 2.1336)
			(layers "B.Cu" "B.Mask" "B.Paste")
			(net "GND")
		)
		(pad "A17" smd rect
			(at -8.605012 3.934968)
			(size 0.381 1.7272)
			(layers "B.Cu" "B.Mask" "B.Paste")
			(net "P2E_PCH_RX_DP")
		)
		(pad "A18" smd rect
			(at -8.005064 3.934968)
			(size 0.381 1.7272)
			(layers "B.Cu" "B.Mask" "B.Paste")
			(net "P2E_PCH_RX_DN")
		)
		(pad "A19" smd rect
			(at -7.405116 4.13512)
			(size 0.381 2.1336)
			(layers "B.Cu" "B.Mask" "B.Paste")
			(net "GND")
		)
		(pad "A20" smd rect
			(at -6.804914 3.934968)
			(size 0.381 1.7272)
			(layers "B.Cu" "B.Mask" "B.Paste")
			(net "P2E_PCH_TX_C_DP")
		)
		(pad "A21" smd rect
			(at -6.204966 3.934968)
			(size 0.381 1.7272)
			(layers "B.Cu" "B.Mask" "B.Paste")
			(net "P2E_PCH_TX_C_DN")
		)
		(pad "A22" smd rect
			(at -5.605018 4.13512)
			(size 0.381 2.1336)
			(layers "B.Cu" "B.Mask" "B.Paste")
			(net "GND")
		)
		(pad "A23" smd rect
			(at -5.00507 3.934968)
			(size 0.381 1.7272)
			(layers "B.Cu" "B.Mask" "B.Paste")
			(net "SMB_BMC_MM6_SCL")
		)
		(pad "A24" smd rect
			(at -4.405122 3.934968)
			(size 0.381 1.7272)
			(layers "B.Cu" "B.Mask" "B.Paste")
			(net "SMB_BMC_MM6_SDA")
		)
		(pad "A25" smd rect
			(at -3.80492 4.13512)
			(size 0.381 2.1336)
			(layers "B.Cu" "B.Mask" "B.Paste")
			(net "SMB_BMC_MM7_SCL")
		)
		(pad "A26" smd rect
			(at -3.204972 3.934968)
			(size 0.381 1.7272)
			(layers "B.Cu" "B.Mask" "B.Paste")
			(net "SMB_BMC_MM7_SDA")
		)
		(pad "A27" smd rect
			(at -2.605024 3.934968)
			(size 0.381 1.7272)
			(layers "B.Cu" "B.Mask" "B.Paste")
			(net "SMB_BMC_MM8_SCL")
		)
		(pad "A28" smd rect
			(at -2.005076 4.13512)
			(size 0.381 2.1336)
			(layers "B.Cu" "B.Mask" "B.Paste")
			(net "SMB_BMC_MM8_SDA")
		)
		(pad "A29" smd rect
			(at 2.005076 4.13512)
			(size 0.381 2.1336)
			(layers "B.Cu" "B.Mask" "B.Paste")
			(net "SMB_BMC_MM9_SCL")
		)
		(pad "A30" smd rect
			(at 2.605024 3.934968)
			(size 0.381 1.7272)
			(layers "B.Cu" "B.Mask" "B.Paste")
			(net "SMB_BMC_MM9_SDA")
		)
		(pad "A31" smd rect
			(at 3.204972 3.934968)
			(size 0.381 1.7272)
			(layers "B.Cu" "B.Mask" "B.Paste")
			(net "SMB_BMC_MM10_SCL")
		)
		(pad "A32" smd rect
			(at 3.80492 4.13512)
			(size 0.381 2.1336)
			(layers "B.Cu" "B.Mask" "B.Paste")
			(net "SMB_BMC_MM10_SDA")
		)
		(pad "A33" smd rect
			(at 4.405122 3.934968)
			(size 0.381 1.7272)
			(layers "B.Cu" "B.Mask" "B.Paste")
			(net "GND")
		)
		(pad "A34" smd rect
			(at 5.00507 3.934968)
			(size 0.381 1.7272)
			(layers "B.Cu" "B.Mask" "B.Paste")
			(net "JTAG_MB_TCK")
		)
		(pad "A35" smd rect
			(at 5.605018 4.13512)
			(size 0.381 2.1336)
			(layers "B.Cu" "B.Mask" "B.Paste")
			(net "JTAG_MB_TMS")
		)
		(pad "A36" smd rect
			(at 6.204966 3.934968)
			(size 0.381 1.7272)
			(layers "B.Cu" "B.Mask" "B.Paste")
			(net "JTAG_MB_TDI")
		)
		(pad "A37" smd rect
			(at 6.804914 3.934968)
			(size 0.381 1.7272)
			(layers "B.Cu" "B.Mask" "B.Paste")
			(net "JTAG_MB_TDO")
		)
		(pad "A38" smd rect
			(at 7.405116 4.13512)
			(size 0.381 2.1336)
			(layers "B.Cu" "B.Mask" "B.Paste")
			(net "SMB_BMC_MM12_SCL")
		)
		(pad "A39" smd rect
			(at 8.005064 3.934968)
			(size 0.381 1.7272)
			(layers "B.Cu" "B.Mask" "B.Paste")
			(net "SMB_BMC_MM12_SDA")
		)
		(pad "A40" smd rect
			(at 8.605012 3.934968)
			(size 0.381 1.7272)
			(layers "B.Cu" "B.Mask" "B.Paste")
			(net "SMB_BMC_MM13_SCL")
		)
		(pad "A41" smd rect
			(at 9.20496 4.13512)
			(size 0.381 2.1336)
			(layers "B.Cu" "B.Mask" "B.Paste")
			(net "SMB_BMC_MM13_SDA")
		)
		(pad "A42" smd rect
			(at 9.804908 4.13512)
			(size 0.381 2.1336)
			(layers "B.Cu" "B.Mask" "B.Paste")
			(net "GND")
		)
		(pad "A43" smd rect
			(at 14.714982 4.13512)
			(size 0.381 2.1336)
			(layers "B.Cu" "B.Mask" "B.Paste")
			(net "FM_JTAG_SEL")
		)
		(pad "A44" smd rect
			(at 15.31493 3.934968)
			(size 0.381 1.7272)
			(layers "B.Cu" "B.Mask" "B.Paste")
			(net "PWRGD_PSU_AC_PWROK_R")
		)
		(pad "A45" smd rect
			(at 15.914878 3.934968)
			(size 0.381 1.7272)
			(layers "B.Cu" "B.Mask" "B.Paste")
			(net "TP_GF_A45")
		)
		(pad "A46" smd rect
			(at 16.51508 4.13512)
			(size 0.381 2.1336)
			(layers "B.Cu" "B.Mask" "B.Paste")
			(net "RST_MB_STBY_N")
		)
		(pad "A47" smd rect
			(at 17.115028 3.934968)
			(size 0.381 1.7272)
			(layers "B.Cu" "B.Mask" "B.Paste")
			(net "SYS_PWRBTN_N")
		)
	)
)
